(kicad_pcb
	(version 20260206)
	(generator "pcbnew")
	(generator_version "10.0")
	(general
		(thickness 1.6)
		(legacy_teardrops no)
	)
	(paper "A4")
	(title_block
		(title "Bryce Canyon_IOM_M2_16342-2_OCP.brd")
		(comment 1 "Bryce Canyon / footprints 76-83 of 1146")
	)
	(layers
		(0 "F.Cu" signal "TOP")
		(4 "In1.Cu" signal "L2GND")
		(6 "In2.Cu" signal "L3")
		(8 "In3.Cu" signal "L4VCC")
		(10 "In4.Cu" signal "L5VCC")
		(12 "In5.Cu" signal "L6")
		(14 "In6.Cu" signal "L7GND")
		(2 "B.Cu" signal "BOTTOM")
		(9 "F.Adhes" user "F.Adhesive")
		(11 "B.Adhes" user "B.Adhesive")
		(13 "F.Paste" user "Package Geometry/Pastemask Top")
		(15 "B.Paste" user "Package Geometry/Pastemask Bottom")
		(5 "F.SilkS" user "Ref Des/Silkscreen Top")
		(7 "B.SilkS" user "Ref Des/Silkscreen Bottom")
		(1 "F.Mask" user "Board Geometry/Soldermask Top")
		(3 "B.Mask" user "Board Geometry/Soldermask Bottom")
		(17 "Dwgs.User" user "User.Drawings")
		(19 "Cmts.User" user "User.Comments")
		(21 "Eco1.User" user "User.Eco1")
		(23 "Eco2.User" user "User.Eco2")
		(25 "Edge.Cuts" user "Board Geometry/Outline")
		(27 "Margin" user)
		(31 "F.CrtYd" user "Package Geometry/Place Bound Top")
		(29 "B.CrtYd" user "Package Geometry/Place Bound Bottom")
		(35 "F.Fab" user "Ref Des/Assembly Top")
		(33 "B.Fab" user "Ref Des/Assembly Bottom")
	)
	(footprint ""
		(layer "F.Cu")
		(at 68.5038 -120.49252 90)
		(property "Reference" "R764"
			(at 0 0 90)
			(layer "F.SilkS")
			(hide yes)
			(effects
				(font
					(size 1.27 1.27)
				)
			)
		)
		(property "Value" "0R2J-2-GP"
			(at 0.064008 -3.993896 90)
			(unlocked yes)
			(layer "F.Fab")
			(hide yes)
			(effects
				(font
					(size 1.016 1.016)
					(thickness 0.1524)
				)
			)
		)
		(property "Device Type" "R402H16"
			(at 0.064008 -5.517896 90)
			(unlocked yes)
			(layer "F.Fab")
			(hide yes)
			(effects
				(font
					(size 1.016 1.016)
					(thickness 0.1524)
				)
			)
		)
		(duplicate_pad_numbers_are_jumpers no)
		(fp_line
			(start 0.508 -0.9398)
			(end -0.508 -0.9398)
			(stroke
				(width 0.1524)
				(type default)
			)
			(layer "F.SilkS")
		)
		(fp_line
			(start -0.508 -0.9398)
			(end -0.508 0.9398)
			(stroke
				(width 0.1524)
				(type default)
			)
			(layer "F.SilkS")
		)
		(fp_rect
			(start -0.508 0.9398)
			(end 0.508 -0.9398)
			(stroke
				(width 0)
				(type default)
			)
			(fill no)
			(layer "F.CrtYd")
		)
		(fp_rect
			(start -0.508 0.9398)
			(end 0.508 -0.9398)
			(stroke
				(width 0)
				(type default)
			)
			(fill no)
			(layer "F.Fab")
		)
		(pad "1" smd custom
			(at 0 -0.4445 90)
			(size 0.1397 0.1397)
			(layers "F.Cu" "F.Mask" "F.Paste")
			(net "FLA1_SPI_RST")
			(options
				(clearance outline)
				(anchor circle)
			)
			(primitives
				(gr_poly
					(pts
						(arc
							(start -0.1778 -0.2794)
							(mid -0.249642 -0.249642)
							(end -0.2794 -0.1778)
						)
						(arc
							(start -0.2794 0.1778)
							(mid -0.249642 0.249642)
							(end -0.1778 0.2794)
						)
						(arc
							(start 0.1778 0.2794)
							(mid 0.249642 0.249642)
							(end 0.2794 0.1778)
						)
						(arc
							(start 0.2794 -0.1778)
							(mid 0.249642 -0.249642)
							(end 0.1778 -0.2794)
						)
					)
					(width 0)
					(fill yes)
				)
			)
		)
		(pad "2" smd custom
			(at 0 0.4445 90)
			(size 0.1397 0.1397)
			(layers "F.Cu" "F.Mask" "F.Paste")
			(net "RST_BMC_EXTRST_N")
			(options
				(clearance outline)
				(anchor circle)
			)
			(primitives
				(gr_poly
					(pts
						(arc
							(start -0.1778 -0.2794)
							(mid -0.249642 -0.249642)
							(end -0.2794 -0.1778)
						)
						(arc
							(start -0.2794 0.1778)
							(mid -0.249642 0.249642)
							(end -0.1778 0.2794)
						)
						(arc
							(start 0.1778 0.2794)
							(mid 0.249642 0.249642)
							(end 0.2794 0.1778)
						)
						(arc
							(start 0.2794 -0.1778)
							(mid 0.249642 -0.249642)
							(end 0.1778 -0.2794)
						)
					)
					(width 0)
					(fill yes)
				)
			)
		)
	)
	(footprint ""
		(layer "F.Cu")
		(at 40.105584 -131.475226 180)
		(property "Reference" "R378"
			(at 0 0 180)
			(layer "F.SilkS")
			(hide yes)
			(effects
				(font
					(size 1.27 1.27)
				)
			)
		)
		(property "Value" "4K7R2F-GP"
			(at 0.064008 -3.993896 180)
			(unlocked yes)
			(layer "F.Fab")
			(hide yes)
			(effects
				(font
					(size 1.016 1.016)
					(thickness 0.1524)
				)
			)
		)
		(property "Device Type" "R402H16"
			(at 0.064008 -5.517896 180)
			(unlocked yes)
			(layer "F.Fab")
			(hide yes)
			(effects
				(font
					(size 1.016 1.016)
					(thickness 0.1524)
				)
			)
		)
		(duplicate_pad_numbers_are_jumpers no)
		(fp_line
			(start 0.508 -0.9398)
			(end -0.508 -0.9398)
			(stroke
				(width 0.1524)
				(type default)
			)
			(layer "F.SilkS")
		)
		(fp_line
			(start -0.508 -0.9398)
			(end -0.508 0.9398)
			(stroke
				(width 0.1524)
				(type default)
			)
			(layer "F.SilkS")
		)
		(fp_rect
			(start -0.508 0.9398)
			(end 0.508 -0.9398)
			(stroke
				(width 0)
				(type default)
			)
			(fill no)
			(layer "F.CrtYd")
		)
		(fp_rect
			(start -0.508 0.9398)
			(end 0.508 -0.9398)
			(stroke
				(width 0)
				(type default)
			)
			(fill no)
			(layer "F.Fab")
		)
		(pad "1" smd custom
			(at 0 -0.4445 180)
			(size 0.1397 0.1397)
			(layers "F.Cu" "F.Mask" "F.Paste")
			(net "P3V3_STBY")
			(options
				(clearance outline)
				(anchor circle)
			)
			(primitives
				(gr_poly
					(pts
						(arc
							(start -0.1778 -0.2794)
							(mid -0.249642 -0.249642)
							(end -0.2794 -0.1778)
						)
						(arc
							(start -0.2794 0.1778)
							(mid -0.249642 0.249642)
							(end -0.1778 0.2794)
						)
						(arc
							(start 0.1778 0.2794)
							(mid 0.249642 0.249642)
							(end 0.2794 0.1778)
						)
						(arc
							(start 0.2794 -0.1778)
							(mid 0.249642 -0.249642)
							(end 0.1778 -0.2794)
						)
					)
					(width 0)
					(fill yes)
				)
			)
		)
		(pad "2" smd custom
			(at 0 0.4445 180)
			(size 0.1397 0.1397)
			(layers "F.Cu" "F.Mask" "F.Paste")
			(net "BMC_GPIOZ6")
			(options
				(clearance outline)
				(anchor circle)
			)
			(primitives
				(gr_poly
					(pts
						(arc
							(start -0.1778 -0.2794)
							(mid -0.249642 -0.249642)
							(end -0.2794 -0.1778)
						)
						(arc
							(start -0.2794 0.1778)
							(mid -0.249642 0.249642)
							(end -0.1778 0.2794)
						)
						(arc
							(start 0.1778 0.2794)
							(mid 0.249642 0.249642)
							(end 0.2794 0.1778)
						)
						(arc
							(start 0.2794 -0.1778)
							(mid 0.249642 -0.249642)
							(end 0.1778 -0.2794)
						)
					)
					(width 0)
					(fill yes)
				)
			)
		)
	)
	(footprint ""
		(layer "F.Cu")
		(at 66.3702 -169.164 90)
		(property "Reference" "C38"
			(at 0 0 90)
			(layer "F.SilkS")
			(hide yes)
			(effects
				(font
					(size 1.27 1.27)
				)
			)
		)
		(property "Value" "SCD1U16V2KX-3GP"
			(at 1.1811 -2.7051 90)
			(unlocked yes)
			(layer "F.Fab")
			(hide yes)
			(effects
				(font
					(size 1.016 1.016)
					(thickness 0.1524)
				)
			)
		)
		(property "Device Type" "C402H22"
			(at 1.1811 -4.2291 90)
			(unlocked yes)
			(layer "F.Fab")
			(hide yes)
			(effects
				(font
					(size 1.016 1.016)
					(thickness 0.1524)
				)
			)
		)
		(duplicate_pad_numbers_are_jumpers no)
		(fp_rect
			(start -0.4318 0.9525)
			(end 0.4318 -0.9525)
			(stroke
				(width 0)
				(type default)
			)
			(fill no)
			(layer "F.CrtYd")
		)
		(fp_rect
			(start -0.4318 0.9525)
			(end 0.4318 -0.9525)
			(stroke
				(width 0)
				(type default)
			)
			(fill no)
			(layer "F.Fab")
		)
		(pad "1" smd custom
			(at 0 -0.4445 90)
			(size 0.1524 0.1524)
			(layers "F.Cu" "F.Mask" "F.Paste")
			(net "Q4_G")
			(options
				(clearance outline)
				(anchor circle)
			)
			(primitives
				(gr_poly
					(pts
						(arc
							(start 0.3048 -0.2032)
							(mid 0.275042 -0.275042)
							(end 0.2032 -0.3048)
						)
						(arc
							(start -0.2032 -0.3048)
							(mid -0.275042 -0.275042)
							(end -0.3048 -0.2032)
						)
						(arc
							(start -0.3048 0.2032)
							(mid -0.275042 0.275042)
							(end -0.2032 0.3048)
						)
						(arc
							(start 0.2032 0.3048)
							(mid 0.275042 0.275042)
							(end 0.3048 0.2032)
						)
					)
					(width 0)
					(fill yes)
				)
			)
		)
		(pad "2" smd custom
			(at 0 0.4445 90)
			(size 0.1524 0.1524)
			(layers "F.Cu" "F.Mask" "F.Paste")
			(net "GND")
			(options
				(clearance outline)
				(anchor circle)
			)
			(primitives
				(gr_poly
					(pts
						(arc
							(start 0.3048 -0.2032)
							(mid 0.275042 -0.275042)
							(end 0.2032 -0.3048)
						)
						(arc
							(start -0.2032 -0.3048)
							(mid -0.275042 -0.275042)
							(end -0.3048 -0.2032)
						)
						(arc
							(start -0.3048 0.2032)
							(mid -0.275042 0.275042)
							(end -0.2032 0.3048)
						)
						(arc
							(start 0.2032 0.3048)
							(mid 0.275042 0.275042)
							(end 0.3048 0.2032)
						)
					)
					(width 0)
					(fill yes)
				)
			)
		)
	)
	(footprint ""
		(layer "F.Cu")
		(at 177.97526 -140.28801 -135)
		(property "Reference" "VIA61"
			(at 0 0 225)
			(layer "F.SilkS")
			(hide yes)
			(effects
				(font
					(size 1.27 1.27)
				)
			)
		)
		(property "Value" "85OHM-8L-1D6MM-L16L18-GP"
			(at 4.064105 0.609655 225)
			(unlocked yes)
			(layer "F.Fab")
			(hide yes)
			(effects
				(font
					(size 1.016 1.016)
					(thickness 0.1524)
				)
			)
		)
		(property "Device Type" "VIA-PCIE-4P-368076"
			(at 4.064105 -0.914474 225)
			(unlocked yes)
			(layer "F.Fab")
			(hide yes)
			(effects
				(font
					(size 1.016 1.016)
					(thickness 0.1524)
				)
			)
		)
		(duplicate_pad_numbers_are_jumpers no)
		(fp_poly
			(pts
				(xy -1.841491 -0.381057) (xy 1.841509 -0.381058) (xy 1.841508 0.380942) (xy -1.841491 0.380942)
			)
			(stroke
				(width 0)
				(type default)
			)
			(fill no)
			(layer "F.CrtYd")
		)
		(fp_poly
			(pts
				(xy -1.841491 -0.381057) (xy 1.841509 -0.381058) (xy 1.841508 0.380942) (xy -1.841491 0.380942)
			)
			(stroke
				(width 0)
				(type default)
			)
			(fill no)
			(layer "F.Fab")
		)
		(pad "1" thru_hole circle
			(at -1.460499 0 225)
			(size 0.508 0.508)
			(drill 0.254)
			(layers "*.Cu" "*.Mask")
			(remove_unused_layers no)
			(net "GND")
			(clearance 0.127)
			(thermal_gap 0.127)
		)
		(pad "2" thru_hole circle
			(at -0.4445 0 225)
			(size 0.508 0.508)
			(drill 0.254)
			(layers "*.Cu" "*.Mask")
			(remove_unused_layers no)
			(net "PCIE_IOM_TO_COMP_13_DP")
			(clearance 0.127)
			(thermal_gap 0.127)
		)
		(pad "3" thru_hole circle
			(at 0.4445 0 225)
			(size 0.508 0.508)
			(drill 0.254)
			(layers "*.Cu" "*.Mask")
			(remove_unused_layers no)
			(net "PCIE_IOM_TO_COMP_13_DN")
			(clearance 0.127)
			(thermal_gap 0.127)
		)
		(pad "4" thru_hole circle
			(at 1.460499 0 225)
			(size 0.508 0.508)
			(drill 0.254)
			(layers "*.Cu" "*.Mask")
			(remove_unused_layers no)
			(net "GND")
			(clearance 0.127)
			(thermal_gap 0.127)
		)
	)
	(footprint ""
		(layer "F.Cu")
		(at 161.708338 -14.886178 180)
		(property "Reference" "R519"
			(at 0 0 180)
			(layer "F.SilkS")
			(hide yes)
			(effects
				(font
					(size 1.27 1.27)
				)
			)
		)
		(property "Value" "1KR2F-3-GP"
			(at 0.064008 -3.993896 180)
			(unlocked yes)
			(layer "F.Fab")
			(hide yes)
			(effects
				(font
					(size 1.016 1.016)
					(thickness 0.1524)
				)
			)
		)
		(property "Device Type" "R402H16"
			(at 0.064008 -5.517896 180)
			(unlocked yes)
			(layer "F.Fab")
			(hide yes)
			(effects
				(font
					(size 1.016 1.016)
					(thickness 0.1524)
				)
			)
		)
		(duplicate_pad_numbers_are_jumpers no)
		(fp_line
			(start 0.508 -0.9398)
			(end -0.508 -0.9398)
			(stroke
				(width 0.1524)
				(type default)
			)
			(layer "F.SilkS")
		)
		(fp_line
			(start -0.508 -0.9398)
			(end -0.508 0.9398)
			(stroke
				(width 0.1524)
				(type default)
			)
			(layer "F.SilkS")
		)
		(fp_rect
			(start -0.508 0.9398)
			(end 0.508 -0.9398)
			(stroke
				(width 0)
				(type default)
			)
			(fill no)
			(layer "F.CrtYd")
		)
		(fp_rect
			(start -0.508 0.9398)
			(end 0.508 -0.9398)
			(stroke
				(width 0)
				(type default)
			)
			(fill no)
			(layer "F.Fab")
		)
		(pad "1" smd custom
			(at 0 -0.4445 180)
			(size 0.1397 0.1397)
			(layers "F.Cu" "F.Mask" "F.Paste")
			(net "P1V8_STBY_SW")
			(options
				(clearance outline)
				(anchor circle)
			)
			(primitives
				(gr_poly
					(pts
						(arc
							(start -0.1778 -0.2794)
							(mid -0.249642 -0.249642)
							(end -0.2794 -0.1778)
						)
						(arc
							(start -0.2794 0.1778)
							(mid -0.249642 0.249642)
							(end -0.1778 0.2794)
						)
						(arc
							(start 0.1778 0.2794)
							(mid 0.249642 0.249642)
							(end 0.2794 0.1778)
						)
						(arc
							(start 0.2794 -0.1778)
							(mid 0.249642 -0.249642)
							(end 0.1778 -0.2794)
						)
					)
					(width 0)
					(fill yes)
				)
			)
		)
		(pad "2" smd custom
			(at 0 0.4445 180)
			(size 0.1397 0.1397)
			(layers "F.Cu" "F.Mask" "F.Paste")
			(net "P1V8_STBY_VFB_R")
			(options
				(clearance outline)
				(anchor circle)
			)
			(primitives
				(gr_poly
					(pts
						(arc
							(start -0.1778 -0.2794)
							(mid -0.249642 -0.249642)
							(end -0.2794 -0.1778)
						)
						(arc
							(start -0.2794 0.1778)
							(mid -0.249642 0.249642)
							(end -0.1778 0.2794)
						)
						(arc
							(start 0.1778 0.2794)
							(mid 0.249642 0.249642)
							(end 0.2794 0.1778)
						)
						(arc
							(start 0.2794 -0.1778)
							(mid 0.249642 -0.249642)
							(end 0.1778 -0.2794)
						)
					)
					(width 0)
					(fill yes)
				)
			)
		)
	)
	(footprint ""
		(layer "F.Cu")
		(at 34.2138 -176.8094 180)
		(property "Reference" "G3"
			(at 0 0 180)
			(layer "F.SilkS")
			(hide yes)
			(effects
				(font
					(size 1.27 1.27)
				)
			)
		)
		(property "Value" "COPPER-CLOSE-GP-U"
			(at 0.0762 -2.8702 180)
			(unlocked yes)
			(layer "F.Fab")
			(hide yes)
			(effects
				(font
					(size 1.016 1.016)
					(thickness 0.1524)
				)
			)
		)
		(property "Device Type" "CON2C-U"
			(at 0.0762 -4.3942 180)
			(unlocked yes)
			(layer "F.Fab")
			(hide yes)
			(effects
				(font
					(size 1.016 1.016)
					(thickness 0.1524)
				)
			)
		)
		(duplicate_pad_numbers_are_jumpers no)
		(fp_rect
			(start -0.9398 0.9652)
			(end 0.9398 -0.9652)
			(stroke
				(width 0)
				(type default)
			)
			(fill no)
			(layer "F.CrtYd")
		)
		(fp_rect
			(start -0.9398 0.9652)
			(end 0.9398 -0.9652)
			(stroke
				(width 0)
				(type default)
			)
			(fill no)
			(layer "F.Fab")
		)
		(pad "1" smd custom
			(at 0 -0.5334 180)
			(size 0.17145 0.17145)
			(layers "F.Cu" "F.Mask" "F.Paste")
			(net "AGND_P3V3_STBY")
			(options
				(clearance outline)
				(anchor circle)
			)
			(primitives
				(gr_poly
					(pts
						(xy -0.127 0.3429) (xy -0.127 0.1651) (xy -0.635 -0.3429) (xy 0.635 -0.3429) (xy 0.127 0.1651)
						(xy 0.127 0.3429)
					)
					(width 0)
					(fill yes)
				)
			)
		)
		(pad "2" smd custom
			(at 0 0.5334 180)
			(size 0.17145 0.17145)
			(layers "F.Cu" "F.Mask" "F.Paste")
			(net "GND")
			(options
				(clearance outline)
				(anchor circle)
			)
			(primitives
				(gr_poly
					(pts
						(xy -0.635 0.3429) (xy -0.127 -0.1651) (xy -0.127 -0.3429) (xy 0.127 -0.3429) (xy 0.127 -0.1651)
						(xy 0.635 0.3429)
					)
					(width 0)
					(fill yes)
				)
			)
		)
	)
	(footprint ""
		(layer "F.Cu")
		(at 30.848046 -175.906938 180)
		(property "Reference" "R497"
			(at 0 0 180)
			(layer "F.SilkS")
			(hide yes)
			(effects
				(font
					(size 1.27 1.27)
				)
			)
		)
		(property "Value" "619KR2F-GP"
			(at 0.064008 -3.993896 180)
			(unlocked yes)
			(layer "F.Fab")
			(hide yes)
			(effects
				(font
					(size 1.016 1.016)
					(thickness 0.1524)
				)
			)
		)
		(property "Device Type" "R402H16"
			(at 0.064008 -5.517896 180)
			(unlocked yes)
			(layer "F.Fab")
			(hide yes)
			(effects
				(font
					(size 1.016 1.016)
					(thickness 0.1524)
				)
			)
		)
		(duplicate_pad_numbers_are_jumpers no)
		(fp_line
			(start 0.508 -0.9398)
			(end -0.508 -0.9398)
			(stroke
				(width 0.1524)
				(type default)
			)
			(layer "F.SilkS")
		)
		(fp_line
			(start -0.508 -0.9398)
			(end -0.508 0.9398)
			(stroke
				(width 0.1524)
				(type default)
			)
			(layer "F.SilkS")
		)
		(fp_rect
			(start -0.508 0.9398)
			(end 0.508 -0.9398)
			(stroke
				(width 0)
				(type default)
			)
			(fill no)
			(layer "F.CrtYd")
		)
		(fp_rect
			(start -0.508 0.9398)
			(end 0.508 -0.9398)
			(stroke
				(width 0)
				(type default)
			)
			(fill no)
			(layer "F.Fab")
		)
		(pad "1" smd custom
			(at 0 -0.4445 180)
			(size 0.1397 0.1397)
			(layers "F.Cu" "F.Mask" "F.Paste")
			(net "AGND_P3V3_STBY")
			(options
				(clearance outline)
				(anchor circle)
			)
			(primitives
				(gr_poly
					(pts
						(arc
							(start -0.1778 -0.2794)
							(mid -0.249642 -0.249642)
							(end -0.2794 -0.1778)
						)
						(arc
							(start -0.2794 0.1778)
							(mid -0.249642 0.249642)
							(end -0.1778 0.2794)
						)
						(arc
							(start 0.1778 0.2794)
							(mid 0.249642 0.249642)
							(end 0.2794 0.1778)
						)
						(arc
							(start 0.2794 -0.1778)
							(mid 0.249642 -0.249642)
							(end 0.1778 -0.2794)
						)
					)
					(width 0)
					(fill yes)
				)
			)
		)
		(pad "2" smd custom
			(at 0 0.4445 180)
			(size 0.1397 0.1397)
			(layers "F.Cu" "F.Mask" "F.Paste")
			(net "P3V3_STBY_RF")
			(options
				(clearance outline)
				(anchor circle)
			)
			(primitives
				(gr_poly
					(pts
						(arc
							(start -0.1778 -0.2794)
							(mid -0.249642 -0.249642)
							(end -0.2794 -0.1778)
						)
						(arc
							(start -0.2794 0.1778)
							(mid -0.249642 0.249642)
							(end -0.1778 0.2794)
						)
						(arc
							(start 0.1778 0.2794)
							(mid 0.249642 0.249642)
							(end 0.2794 0.1778)
						)
						(arc
							(start 0.2794 -0.1778)
							(mid 0.249642 -0.249642)
							(end 0.1778 -0.2794)
						)
					)
					(width 0)
					(fill yes)
				)
			)
		)
	)
	(footprint ""
		(layer "F.Cu")
		(at 71.81723 -142.670276 90)
		(property "Reference" "R52"
			(at 0 0 90)
			(layer "F.SilkS")
			(hide yes)
			(effects
				(font
					(size 1.27 1.27)
				)
			)
		)
		(property "Value" "33R2F-3-GP"
			(at 0.064008 -3.993896 90)
			(unlocked yes)
			(layer "F.Fab")
			(hide yes)
			(effects
				(font
					(size 1.016 1.016)
					(thickness 0.1524)
				)
			)
		)
		(property "Device Type" "R402H16"
			(at 0.064008 -5.517896 90)
			(unlocked yes)
			(layer "F.Fab")
			(hide yes)
			(effects
				(font
					(size 1.016 1.016)
					(thickness 0.1524)
				)
			)
		)
		(duplicate_pad_numbers_are_jumpers no)
		(fp_line
			(start 0.508 -0.9398)
			(end -0.508 -0.9398)
			(stroke
				(width 0.1524)
				(type default)
			)
			(layer "F.SilkS")
		)
		(fp_line
			(start -0.508 -0.9398)
			(end -0.508 0.9398)
			(stroke
				(width 0.1524)
				(type default)
			)
			(layer "F.SilkS")
		)
		(fp_rect
			(start -0.508 0.9398)
			(end 0.508 -0.9398)
			(stroke
				(width 0)
				(type default)
			)
			(fill no)
			(layer "F.CrtYd")
		)
		(fp_rect
			(start -0.508 0.9398)
			(end 0.508 -0.9398)
			(stroke
				(width 0)
				(type default)
			)
			(fill no)
			(layer "F.Fab")
		)
		(pad "1" smd custom
			(at 0 -0.4445 90)
			(size 0.1397 0.1397)
			(layers "F.Cu" "F.Mask" "F.Paste")
			(net "FP_PWRBTN")
			(options
				(clearance outline)
				(anchor circle)
			)
			(primitives
				(gr_poly
					(pts
						(arc
							(start -0.1778 -0.2794)
							(mid -0.249642 -0.249642)
							(end -0.2794 -0.1778)
						)
						(arc
							(start -0.2794 0.1778)
							(mid -0.249642 0.249642)
							(end -0.1778 0.2794)
						)
						(arc
							(start 0.1778 0.2794)
							(mid 0.249642 0.249642)
							(end 0.2794 0.1778)
						)
						(arc
							(start 0.2794 -0.1778)
							(mid 0.249642 -0.249642)
							(end 0.1778 -0.2794)
						)
					)
					(width 0)
					(fill yes)
				)
			)
		)
		(pad "2" smd custom
			(at 0 0.4445 90)
			(size 0.1397 0.1397)
			(layers "F.Cu" "F.Mask" "F.Paste")
			(net "PWRBTN_OUT_N")
			(options
				(clearance outline)
				(anchor circle)
			)
			(primitives
				(gr_poly
					(pts
						(arc
							(start -0.1778 -0.2794)
							(mid -0.249642 -0.249642)
							(end -0.2794 -0.1778)
						)
						(arc
							(start -0.2794 0.1778)
							(mid -0.249642 0.249642)
							(end -0.1778 0.2794)
						)
						(arc
							(start 0.1778 0.2794)
							(mid 0.249642 0.249642)
							(end 0.2794 0.1778)
						)
						(arc
							(start 0.2794 -0.1778)
							(mid 0.249642 -0.249642)
							(end 0.1778 -0.2794)
						)
					)
					(width 0)
					(fill yes)
				)
			)
		)
	)
)
